(kicad_pcb
	(version 20260206)
	(generator "pcbnew")
	(generator_version "10.0")
	(general
		(thickness 1.6)
		(legacy_teardrops no)
	)
	(paper "A4")
	(title_block
		(title "Bryce Canyon_R.DPB_16317-1_OCP.brd")
		(comment 1 "Bryce Canyon / footprints 1968-1976 of 2099")
	)
	(layers
		(0 "F.Cu" signal "TOP")
		(4 "In1.Cu" signal "L2GND")
		(6 "In2.Cu" signal "L3")
		(8 "In3.Cu" signal "L4VCC")
		(10 "In4.Cu" signal "L5VCC")
		(12 "In5.Cu" signal "L6")
		(14 "In6.Cu" signal "L7GND")
		(2 "B.Cu" signal "BOTTOM")
		(9 "F.Adhes" user "F.Adhesive")
		(11 "B.Adhes" user "B.Adhesive")
		(13 "F.Paste" user "Package Geometry/Pastemask Top")
		(15 "B.Paste" user "Package Geometry/Pastemask Bottom")
		(5 "F.SilkS" user "Ref Des/Silkscreen Top")
		(7 "B.SilkS" user "Ref Des/Silkscreen Bottom")
		(1 "F.Mask" user "Board Geometry/Soldermask Top")
		(3 "B.Mask" user "Board Geometry/Soldermask Bottom")
		(17 "Dwgs.User" user "User.Drawings")
		(19 "Cmts.User" user "User.Comments")
		(21 "Eco1.User" user "User.Eco1")
		(23 "Eco2.User" user "User.Eco2")
		(25 "Edge.Cuts" user "Board Geometry/Outline")
		(27 "Margin" user)
		(31 "F.CrtYd" user "Package Geometry/Place Bound Top")
		(29 "B.CrtYd" user "Package Geometry/Place Bound Bottom")
		(35 "F.Fab" user "Ref Des/Assembly Top")
		(33 "B.Fab" user "Ref Des/Assembly Bottom")
	)
	(footprint ""
		(layer "B.Cu")
		(at 35.20186 -111.833406 180)
		(property "Reference" "C637"
			(at 0 0 0)
			(layer "B.SilkS")
			(hide yes)
			(effects
				(font
					(size 1.27 1.27)
				)
				(justify mirror)
			)
		)
		(property "Value" "SC10U16V5KX-7-GP-U"
			(at 0.0762 -6.1214 180)
			(unlocked yes)
			(layer "B.Fab")
			(hide yes)
			(effects
				(font
					(size 1.016 1.016)
					(thickness 0.1524)
				)
				(justify mirror)
			)
		)
		(property "Device Type" "C805H58"
			(at 0.0762 -8.1534 180)
			(unlocked yes)
			(layer "B.Fab")
			(hide yes)
			(effects
				(font
					(size 1.016 1.016)
					(thickness 0.1524)
				)
				(justify mirror)
			)
		)
		(duplicate_pad_numbers_are_jumpers no)
		(fp_line
			(start -0.635 0)
			(end 0.635 0)
			(stroke
				(width 0.508)
				(type default)
			)
			(layer "B.SilkS")
		)
		(fp_rect
			(start 0.9652 1.778)
			(end -0.9652 -1.778)
			(stroke
				(width 0)
				(type default)
			)
			(fill no)
			(layer "B.CrtYd")
		)
		(fp_poly
			(pts
				(xy 0.9652 -1.778) (xy -0.9652 -1.778) (xy -0.9652 1.778) (xy 0.9652 1.778)
			)
			(stroke
				(width 0)
				(type default)
			)
			(fill no)
			(layer "B.Fab")
		)
		(pad "1" smd rect
			(at 0 -0.9652)
			(size 1.397 1.143)
			(layers "B.Cu" "B.Mask" "B.Paste")
			(net "P12V_B_2_VIN_U32")
		)
		(pad "2" smd rect
			(at 0 0.9652)
			(size 1.397 1.143)
			(layers "B.Cu" "B.Mask" "B.Paste")
			(net "GND")
		)
	)
	(footprint ""
		(layer "B.Cu")
		(at 46.675802 -228.35235 180)
		(property "Reference" "C634"
			(at 0 0 0)
			(layer "B.SilkS")
			(hide yes)
			(effects
				(font
					(size 1.27 1.27)
				)
				(justify mirror)
			)
		)
		(property "Value" "SC10U16V5KX-7-GP-U"
			(at 0.0762 -6.1214 180)
			(unlocked yes)
			(layer "B.Fab")
			(hide yes)
			(effects
				(font
					(size 1.016 1.016)
					(thickness 0.1524)
				)
				(justify mirror)
			)
		)
		(property "Device Type" "C805H58"
			(at 0.0762 -8.1534 180)
			(unlocked yes)
			(layer "B.Fab")
			(hide yes)
			(effects
				(font
					(size 1.016 1.016)
					(thickness 0.1524)
				)
				(justify mirror)
			)
		)
		(duplicate_pad_numbers_are_jumpers no)
		(fp_line
			(start -0.635 0)
			(end 0.635 0)
			(stroke
				(width 0.508)
				(type default)
			)
			(layer "B.SilkS")
		)
		(fp_rect
			(start 0.9652 1.778)
			(end -0.9652 -1.778)
			(stroke
				(width 0)
				(type default)
			)
			(fill no)
			(layer "B.CrtYd")
		)
		(fp_poly
			(pts
				(xy 0.9652 -1.778) (xy -0.9652 -1.778) (xy -0.9652 1.778) (xy 0.9652 1.778)
			)
			(stroke
				(width 0)
				(type default)
			)
			(fill no)
			(layer "B.Fab")
		)
		(pad "1" smd rect
			(at 0 -0.9652)
			(size 1.397 1.143)
			(layers "B.Cu" "B.Mask" "B.Paste")
			(net "P5V_B_1")
		)
		(pad "2" smd rect
			(at 0 0.9652)
			(size 1.397 1.143)
			(layers "B.Cu" "B.Mask" "B.Paste")
			(net "GND")
		)
	)
	(footprint ""
		(layer "B.Cu")
		(at 45.97146 -118.361206)
		(property "Reference" "G4"
			(at 0 0 0)
			(layer "B.SilkS")
			(hide yes)
			(effects
				(font
					(size 1.27 1.27)
				)
				(justify mirror)
			)
		)
		(property "Value" "COPPER-CLOSE-GP-U"
			(at -0.0762 -2.8702 0)
			(unlocked yes)
			(layer "B.Fab")
			(hide yes)
			(effects
				(font
					(size 1.016 1.016)
					(thickness 0.1524)
				)
				(justify mirror)
			)
		)
		(property "Device Type" "CON2C-U"
			(at -0.0762 -4.3942 0)
			(unlocked yes)
			(layer "B.Fab")
			(hide yes)
			(effects
				(font
					(size 1.016 1.016)
					(thickness 0.1524)
				)
				(justify mirror)
			)
		)
		(duplicate_pad_numbers_are_jumpers no)
		(fp_rect
			(start 0.9398 0.9652)
			(end -0.9398 -0.9652)
			(stroke
				(width 0)
				(type default)
			)
			(fill no)
			(layer "B.CrtYd")
		)
		(fp_rect
			(start 0.9398 0.9652)
			(end -0.9398 -0.9652)
			(stroke
				(width 0)
				(type default)
			)
			(fill no)
			(layer "B.Fab")
		)
		(pad "1" smd custom
			(at 0 -0.5334 180)
			(size 0.17145 0.17145)
			(layers "B.Cu" "B.Mask" "B.Paste")
			(net "AGND_P5V_B_2")
			(options
				(clearance outline)
				(anchor circle)
			)
			(primitives
				(gr_poly
					(pts
						(xy -0.127 -0.3429) (xy -0.127 -0.1651) (xy -0.635 0.3429) (xy 0.635 0.3429) (xy 0.127 -0.1651)
						(xy 0.127 -0.3429)
					)
					(width 0)
					(fill yes)
				)
			)
		)
		(pad "2" smd custom
			(at 0 0.5334 180)
			(size 0.17145 0.17145)
			(layers "B.Cu" "B.Mask" "B.Paste")
			(net "GND")
			(options
				(clearance outline)
				(anchor circle)
			)
			(primitives
				(gr_poly
					(pts
						(xy -0.635 -0.3429) (xy -0.127 0.1651) (xy -0.127 0.3429) (xy 0.127 0.3429) (xy 0.127 0.1651)
						(xy 0.635 -0.3429)
					)
					(width 0)
					(fill yes)
				)
			)
		)
	)
	(footprint ""
		(layer "B.Cu")
		(at 49.308258 -118.507256 90)
		(property "Reference" "R1127"
			(at 0 0 90)
			(layer "B.SilkS")
			(hide yes)
			(effects
				(font
					(size 1.27 1.27)
				)
				(justify mirror)
			)
		)
		(property "Value" "71K5R2F-GP"
			(at -0.064008 -3.993896 90)
			(unlocked yes)
			(layer "B.Fab")
			(hide yes)
			(effects
				(font
					(size 1.016 1.016)
					(thickness 0.1524)
				)
				(justify mirror)
			)
		)
		(property "Device Type" "R402H16"
			(at -0.064008 -5.517896 90)
			(unlocked yes)
			(layer "B.Fab")
			(hide yes)
			(effects
				(font
					(size 1.016 1.016)
					(thickness 0.1524)
				)
				(justify mirror)
			)
		)
		(duplicate_pad_numbers_are_jumpers no)
		(fp_line
			(start 0.508 -0.9398)
			(end 0.508 0.9398)
			(stroke
				(width 0.1524)
				(type default)
			)
			(layer "B.SilkS")
		)
		(fp_line
			(start -0.508 -0.9398)
			(end 0.508 -0.9398)
			(stroke
				(width 0.1524)
				(type default)
			)
			(layer "B.SilkS")
		)
		(fp_rect
			(start 0.508 0.9398)
			(end -0.508 -0.9398)
			(stroke
				(width 0)
				(type default)
			)
			(fill no)
			(layer "B.CrtYd")
		)
		(fp_rect
			(start 0.508 0.9398)
			(end -0.508 -0.9398)
			(stroke
				(width 0)
				(type default)
			)
			(fill no)
			(layer "B.Fab")
		)
		(pad "1" smd custom
			(at 0 -0.4445 270)
			(size 0.1397 0.1397)
			(layers "B.Cu" "B.Mask" "B.Paste")
			(net "P5V_B_2_VFB")
			(options
				(clearance outline)
				(anchor circle)
			)
			(primitives
				(gr_poly
					(pts
						(arc
							(start -0.1778 0.2794)
							(mid -0.249642 0.249642)
							(end -0.2794 0.1778)
						)
						(arc
							(start -0.2794 -0.1778)
							(mid -0.249642 -0.249642)
							(end -0.1778 -0.2794)
						)
						(arc
							(start 0.1778 -0.2794)
							(mid 0.249642 -0.249642)
							(end 0.2794 -0.1778)
						)
						(arc
							(start 0.2794 0.1778)
							(mid 0.249642 0.249642)
							(end 0.1778 0.2794)
						)
					)
					(width 0)
					(fill yes)
				)
			)
		)
		(pad "2" smd custom
			(at 0 0.4445 270)
			(size 0.1397 0.1397)
			(layers "B.Cu" "B.Mask" "B.Paste")
			(net "P5V_B_2_VFB_R")
			(options
				(clearance outline)
				(anchor circle)
			)
			(primitives
				(gr_poly
					(pts
						(arc
							(start -0.1778 0.2794)
							(mid -0.249642 0.249642)
							(end -0.2794 0.1778)
						)
						(arc
							(start -0.2794 -0.1778)
							(mid -0.249642 -0.249642)
							(end -0.1778 -0.2794)
						)
						(arc
							(start 0.1778 -0.2794)
							(mid 0.249642 -0.249642)
							(end 0.2794 -0.1778)
						)
						(arc
							(start 0.2794 0.1778)
							(mid 0.249642 0.249642)
							(end 0.1778 0.2794)
						)
					)
					(width 0)
					(fill yes)
				)
			)
		)
	)
	(footprint ""
		(layer "B.Cu")
		(at 55.769002 -117.916452 180)
		(property "Reference" "R1122"
			(at 0 0 0)
			(layer "B.SilkS")
			(hide yes)
			(effects
				(font
					(size 1.27 1.27)
				)
				(justify mirror)
			)
		)
		(property "Value" "2K7R2F-GP"
			(at -0.064008 -3.993896 180)
			(unlocked yes)
			(layer "B.Fab")
			(hide yes)
			(effects
				(font
					(size 1.016 1.016)
					(thickness 0.1524)
				)
				(justify mirror)
			)
		)
		(property "Device Type" "R402H16"
			(at -0.064008 -5.517896 180)
			(unlocked yes)
			(layer "B.Fab")
			(hide yes)
			(effects
				(font
					(size 1.016 1.016)
					(thickness 0.1524)
				)
				(justify mirror)
			)
		)
		(duplicate_pad_numbers_are_jumpers no)
		(fp_line
			(start 0.508 -0.9398)
			(end 0.508 0.9398)
			(stroke
				(width 0.1524)
				(type default)
			)
			(layer "B.SilkS")
		)
		(fp_line
			(start -0.508 -0.9398)
			(end 0.508 -0.9398)
			(stroke
				(width 0.1524)
				(type default)
			)
			(layer "B.SilkS")
		)
		(fp_rect
			(start 0.508 0.9398)
			(end -0.508 -0.9398)
			(stroke
				(width 0)
				(type default)
			)
			(fill no)
			(layer "B.CrtYd")
		)
		(fp_rect
			(start 0.508 0.9398)
			(end -0.508 -0.9398)
			(stroke
				(width 0)
				(type default)
			)
			(fill no)
			(layer "B.Fab")
		)
		(pad "1" smd custom
			(at 0 -0.4445)
			(size 0.1397 0.1397)
			(layers "B.Cu" "B.Mask" "B.Paste")
			(net "P5V_B_2_LL")
			(options
				(clearance outline)
				(anchor circle)
			)
			(primitives
				(gr_poly
					(pts
						(arc
							(start -0.1778 0.2794)
							(mid -0.249642 0.249642)
							(end -0.2794 0.1778)
						)
						(arc
							(start -0.2794 -0.1778)
							(mid -0.249642 -0.249642)
							(end -0.1778 -0.2794)
						)
						(arc
							(start 0.1778 -0.2794)
							(mid 0.249642 -0.249642)
							(end 0.2794 -0.1778)
						)
						(arc
							(start 0.2794 0.1778)
							(mid 0.249642 0.249642)
							(end 0.1778 0.2794)
						)
					)
					(width 0)
					(fill yes)
				)
			)
		)
		(pad "2" smd custom
			(at 0 0.4445)
			(size 0.1397 0.1397)
			(layers "B.Cu" "B.Mask" "B.Paste")
			(net "P5V_B_2_LL_R")
			(options
				(clearance outline)
				(anchor circle)
			)
			(primitives
				(gr_poly
					(pts
						(arc
							(start -0.1778 0.2794)
							(mid -0.249642 0.249642)
							(end -0.2794 0.1778)
						)
						(arc
							(start -0.2794 -0.1778)
							(mid -0.249642 -0.249642)
							(end -0.1778 -0.2794)
						)
						(arc
							(start 0.1778 -0.2794)
							(mid 0.249642 -0.249642)
							(end 0.2794 -0.1778)
						)
						(arc
							(start 0.2794 0.1778)
							(mid 0.249642 0.249642)
							(end 0.1778 0.2794)
						)
					)
					(width 0)
					(fill yes)
				)
			)
		)
	)
	(footprint ""
		(layer "B.Cu")
		(at 451.551802 -225.43135 90)
		(property "Reference" "C663"
			(at 0 0 90)
			(layer "B.SilkS")
			(hide yes)
			(effects
				(font
					(size 1.27 1.27)
				)
				(justify mirror)
			)
		)
		(property "Value" "SC1U16V3KX-5GP"
			(at 0 -2.8194 90)
			(unlocked yes)
			(layer "B.Fab")
			(hide yes)
			(effects
				(font
					(size 1.016 1.016)
					(thickness 0.1524)
				)
				(justify mirror)
			)
		)
		(property "Device Type" "C603H36"
			(at 0 -4.3434 90)
			(unlocked yes)
			(layer "B.Fab")
			(hide yes)
			(effects
				(font
					(size 1.016 1.016)
					(thickness 0.1524)
				)
				(justify mirror)
			)
		)
		(duplicate_pad_numbers_are_jumpers no)
		(fp_line
			(start -0.508 0)
			(end 0.508 0)
			(stroke
				(width 0.2032)
				(type default)
			)
			(layer "B.SilkS")
		)
		(fp_rect
			(start 0.5842 1.3335)
			(end -0.5842 -1.3335)
			(stroke
				(width 0)
				(type default)
			)
			(fill no)
			(layer "B.CrtYd")
		)
		(fp_rect
			(start 0.5842 1.3335)
			(end -0.5842 -1.3335)
			(stroke
				(width 0)
				(type default)
			)
			(fill no)
			(layer "B.Fab")
		)
		(pad "1" smd custom
			(at 0 -0.762 270)
			(size 0.2159 0.2159)
			(layers "B.Cu" "B.Mask" "B.Paste")
			(net "GND")
			(options
				(clearance outline)
				(anchor circle)
			)
			(primitives
				(gr_poly
					(pts
						(arc
							(start -0.3302 0.4318)
							(mid -0.402042 0.402042)
							(end -0.4318 0.3302)
						)
						(arc
							(start -0.4318 -0.3302)
							(mid -0.402042 -0.402042)
							(end -0.3302 -0.4318)
						)
						(arc
							(start 0.3302 -0.4318)
							(mid 0.402042 -0.402042)
							(end 0.4318 -0.3302)
						)
						(arc
							(start 0.4318 0.3302)
							(mid 0.402042 0.402042)
							(end 0.3302 0.4318)
						)
					)
					(width 0)
					(fill yes)
				)
			)
		)
		(pad "2" smd custom
			(at 0 0.762 270)
			(size 0.2159 0.2159)
			(layers "B.Cu" "B.Mask" "B.Paste")
			(net "P5V_B_3_VREG")
			(options
				(clearance outline)
				(anchor circle)
			)
			(primitives
				(gr_poly
					(pts
						(arc
							(start -0.3302 0.4318)
							(mid -0.402042 0.402042)
							(end -0.4318 0.3302)
						)
						(arc
							(start -0.4318 -0.3302)
							(mid -0.402042 -0.402042)
							(end -0.3302 -0.4318)
						)
						(arc
							(start 0.3302 -0.4318)
							(mid 0.402042 -0.402042)
							(end 0.4318 -0.3302)
						)
						(arc
							(start 0.4318 0.3302)
							(mid 0.402042 0.402042)
							(end 0.3302 0.4318)
						)
					)
					(width 0)
					(fill yes)
				)
			)
		)
	)
	(footprint ""
		(layer "B.Cu")
		(at 239.903 -286.004 180)
		(property "Reference" "C704"
			(at 0 0 0)
			(layer "B.SilkS")
			(hide yes)
			(effects
				(font
					(size 1.27 1.27)
				)
				(justify mirror)
			)
		)
		(property "Value" "SC10U6D3V5KX-4GP"
			(at 0.0762 -6.1214 180)
			(unlocked yes)
			(layer "B.Fab")
			(hide yes)
			(effects
				(font
					(size 1.016 1.016)
					(thickness 0.1524)
				)
				(justify mirror)
			)
		)
		(property "Device Type" "C805H58"
			(at 0.0762 -8.1534 180)
			(unlocked yes)
			(layer "B.Fab")
			(hide yes)
			(effects
				(font
					(size 1.016 1.016)
					(thickness 0.1524)
				)
				(justify mirror)
			)
		)
		(duplicate_pad_numbers_are_jumpers no)
		(fp_line
			(start -0.635 0)
			(end 0.635 0)
			(stroke
				(width 0.508)
				(type default)
			)
			(layer "B.SilkS")
		)
		(fp_rect
			(start 0.9652 1.778)
			(end -0.9652 -1.778)
			(stroke
				(width 0)
				(type default)
			)
			(fill no)
			(layer "B.CrtYd")
		)
		(fp_poly
			(pts
				(xy 0.9652 -1.778) (xy -0.9652 -1.778) (xy -0.9652 1.778) (xy 0.9652 1.778)
			)
			(stroke
				(width 0)
				(type default)
			)
			(fill no)
			(layer "B.Fab")
		)
		(pad "1" smd rect
			(at 0 -0.9652)
			(size 1.397 1.143)
			(layers "B.Cu" "B.Mask" "B.Paste")
			(net "P3V3_STBY_B")
		)
		(pad "2" smd rect
			(at 0 0.9652)
			(size 1.397 1.143)
			(layers "B.Cu" "B.Mask" "B.Paste")
			(net "GND")
		)
	)
	(footprint ""
		(layer "B.Cu")
		(at 257.360674 -278.478234)
		(property "Reference" "R1183"
			(at 0 0 0)
			(layer "B.SilkS")
			(hide yes)
			(effects
				(font
					(size 1.27 1.27)
				)
				(justify mirror)
			)
		)
		(property "Value" "15KR2F-GP"
			(at -0.064008 -3.993896 0)
			(unlocked yes)
			(layer "B.Fab")
			(hide yes)
			(effects
				(font
					(size 1.016 1.016)
					(thickness 0.1524)
				)
				(justify mirror)
			)
		)
		(property "Device Type" "R402H16"
			(at -0.064008 -5.517896 0)
			(unlocked yes)
			(layer "B.Fab")
			(hide yes)
			(effects
				(font
					(size 1.016 1.016)
					(thickness 0.1524)
				)
				(justify mirror)
			)
		)
		(duplicate_pad_numbers_are_jumpers no)
		(fp_line
			(start -0.508 -0.9398)
			(end 0.508 -0.9398)
			(stroke
				(width 0.1524)
				(type default)
			)
			(layer "B.SilkS")
		)
		(fp_line
			(start 0.508 -0.9398)
			(end 0.508 0.9398)
			(stroke
				(width 0.1524)
				(type default)
			)
			(layer "B.SilkS")
		)
		(fp_rect
			(start 0.508 0.9398)
			(end -0.508 -0.9398)
			(stroke
				(width 0)
				(type default)
			)
			(fill no)
			(layer "B.CrtYd")
		)
		(fp_rect
			(start 0.508 0.9398)
			(end -0.508 -0.9398)
			(stroke
				(width 0)
				(type default)
			)
			(fill no)
			(layer "B.Fab")
		)
		(pad "1" smd custom
			(at 0 -0.4445 180)
			(size 0.1397 0.1397)
			(layers "B.Cu" "B.Mask" "B.Paste")
			(net "PWRGD_P3V3_STBY")
			(options
				(clearance outline)
				(anchor circle)
			)
			(primitives
				(gr_poly
					(pts
						(arc
							(start -0.1778 0.2794)
							(mid -0.249642 0.249642)
							(end -0.2794 0.1778)
						)
						(arc
							(start -0.2794 -0.1778)
							(mid -0.249642 -0.249642)
							(end -0.1778 -0.2794)
						)
						(arc
							(start 0.1778 -0.2794)
							(mid 0.249642 -0.249642)
							(end 0.2794 -0.1778)
						)
						(arc
							(start 0.2794 0.1778)
							(mid 0.249642 0.249642)
							(end 0.1778 0.2794)
						)
					)
					(width 0)
					(fill yes)
				)
			)
		)
		(pad "2" smd custom
			(at 0 0.4445 180)
			(size 0.1397 0.1397)
			(layers "B.Cu" "B.Mask" "B.Paste")
			(net "GND")
			(options
				(clearance outline)
				(anchor circle)
			)
			(primitives
				(gr_poly
					(pts
						(arc
							(start -0.1778 0.2794)
							(mid -0.249642 0.249642)
							(end -0.2794 0.1778)
						)
						(arc
							(start -0.2794 -0.1778)
							(mid -0.249642 -0.249642)
							(end -0.1778 -0.2794)
						)
						(arc
							(start 0.1778 -0.2794)
							(mid 0.249642 -0.249642)
							(end 0.2794 -0.1778)
						)
						(arc
							(start 0.2794 0.1778)
							(mid 0.249642 0.249642)
							(end 0.1778 0.2794)
						)
					)
					(width 0)
					(fill yes)
				)
			)
		)
	)
	(footprint ""
		(layer "B.Cu")
		(at 450.027802 -223.01835 180)
		(property "Reference" "C653"
			(at 0 0 0)
			(layer "B.SilkS")
			(hide yes)
			(effects
				(font
					(size 1.27 1.27)
				)
				(justify mirror)
			)
		)
		(property "Value" "SC10U16V5KX-7-GP-U"
			(at 0.0762 -6.1214 180)
			(unlocked yes)
			(layer "B.Fab")
			(hide yes)
			(effects
				(font
					(size 1.016 1.016)
					(thickness 0.1524)
				)
				(justify mirror)
			)
		)
		(property "Device Type" "C805H58"
			(at 0.0762 -8.1534 180)
			(unlocked yes)
			(layer "B.Fab")
			(hide yes)
			(effects
				(font
					(size 1.016 1.016)
					(thickness 0.1524)
				)
				(justify mirror)
			)
		)
		(duplicate_pad_numbers_are_jumpers no)
		(fp_line
			(start -0.635 0)
			(end 0.635 0)
			(stroke
				(width 0.508)
				(type default)
			)
			(layer "B.SilkS")
		)
		(fp_rect
			(start 0.9652 1.778)
			(end -0.9652 -1.778)
			(stroke
				(width 0)
				(type default)
			)
			(fill no)
			(layer "B.CrtYd")
		)
		(fp_poly
			(pts
				(xy 0.9652 -1.778) (xy -0.9652 -1.778) (xy -0.9652 1.778) (xy 0.9652 1.778)
			)
			(stroke
				(width 0)
				(type default)
			)
			(fill no)
			(layer "B.Fab")
		)
		(pad "1" smd rect
			(at 0 -0.9652)
			(size 1.397 1.143)
			(layers "B.Cu" "B.Mask" "B.Paste")
			(net "P12V_B_3_VIN_U33")
		)
		(pad "2" smd rect
			(at 0 0.9652)
			(size 1.397 1.143)
			(layers "B.Cu" "B.Mask" "B.Paste")
			(net "GND")
		)
	)
)
